(kicad_pcb
	(version 20260206)
	(generator "pcbnew")
	(generator_version "10.0")
	(general
		(thickness 1.6)
		(legacy_teardrops no)
	)
	(paper "A4")
	(title_block
		(title "01162023_DA0F0TEBIF0_F0T_Expander_BD_F_brd_V02_OCP.brd")
		(comment 1 "Grand Teton / footprints 2799-2804 of 9728")
	)
	(layers
		(0 "F.Cu" signal "TOP")
		(4 "In1.Cu" signal "GND")
		(6 "In2.Cu" signal "VCC")
		(8 "In3.Cu" signal "VCC1")
		(10 "In4.Cu" signal "GND1")
		(12 "In5.Cu" signal "IN1")
		(14 "In6.Cu" signal "GND2")
		(16 "In7.Cu" signal "IN2")
		(18 "In8.Cu" signal "GND3")
		(20 "In9.Cu" signal "IN3")
		(22 "In10.Cu" signal "GND4")
		(24 "In11.Cu" signal "IN4")
		(26 "In12.Cu" signal "GND5")
		(28 "In13.Cu" signal "IN5")
		(30 "In14.Cu" signal "GND6")
		(32 "In15.Cu" signal "IN6")
		(34 "In16.Cu" signal "GND7")
		(2 "B.Cu" signal "BOTTOM")
		(9 "F.Adhes" user "F.Adhesive")
		(11 "B.Adhes" user "B.Adhesive")
		(13 "F.Paste" user "Package Geometry/Pastemask Top")
		(15 "B.Paste" user "Package Geometry/Pastemask Bottom")
		(5 "F.SilkS" user "Ref Des/Silkscreen Top")
		(7 "B.SilkS" user "Ref Des/Silkscreen Bottom")
		(1 "F.Mask" user "Board Geometry/Soldermask Top")
		(3 "B.Mask" user "Board Geometry/Soldermask Bottom")
		(17 "Dwgs.User" user "User.Drawings")
		(19 "Cmts.User" user "User.Comments")
		(21 "Eco1.User" user "User.Eco1")
		(23 "Eco2.User" user "User.Eco2")
		(25 "Edge.Cuts" user "Board Geometry/Outline")
		(27 "Margin" user)
		(31 "F.CrtYd" user "Package Geometry/Place Bound Top")
		(29 "B.CrtYd" user "Package Geometry/Place Bound Bottom")
		(35 "F.Fab" user "Ref Des/Assembly Top")
		(33 "B.Fab" user "Ref Des/Assembly Bottom")
	)
	(footprint ""
		(layer "F.Cu")
		(at 142.343886 -44.87291)
		(property "Reference" "R550"
			(at 0 0 0)
			(layer "F.SilkS")
			(hide yes)
			(effects
				(font
					(size 1.27 1.27)
				)
			)
		)
		(property "Value" ""
			(at 0 0 0)
			(layer "F.Fab")
			(effects
				(font
					(size 1.27 1.27)
				)
			)
		)
		(duplicate_pad_numbers_are_jumpers no)
		(fp_line
			(start -0.7874 -0.4064)
			(end 0.7874 -0.4064)
			(stroke
				(width 0.1524)
				(type default)
			)
			(layer "F.SilkS")
		)
		(fp_line
			(start -0.7874 0.4064)
			(end -0.7874 -0.4064)
			(stroke
				(width 0.1524)
				(type default)
			)
			(layer "F.SilkS")
		)
		(fp_line
			(start 0.7874 -0.4064)
			(end 0.7874 0.4064)
			(stroke
				(width 0.1524)
				(type default)
			)
			(layer "F.SilkS")
		)
		(fp_line
			(start 0.7874 0.4064)
			(end -0.7874 0.4064)
			(stroke
				(width 0.1524)
				(type default)
			)
			(layer "F.SilkS")
		)
		(fp_line
			(start -0.67945 -0.305054)
			(end -0.12065 -0.305054)
			(stroke
				(width 0.1)
				(type default)
			)
			(layer "F.Fab")
		)
		(fp_line
			(start -0.67945 0.3048)
			(end -0.67945 -0.305054)
			(stroke
				(width 0.1)
				(type default)
			)
			(layer "F.Fab")
		)
		(fp_line
			(start -0.12065 -0.305054)
			(end -0.12065 -0.2794)
			(stroke
				(width 0.1)
				(type default)
			)
			(layer "F.Fab")
		)
		(fp_line
			(start -0.12065 -0.2794)
			(end 0.12065 -0.2794)
			(stroke
				(width 0.1)
				(type default)
			)
			(layer "F.Fab")
		)
		(fp_line
			(start -0.12065 0.2794)
			(end -0.12065 0.3048)
			(stroke
				(width 0.1)
				(type default)
			)
			(layer "F.Fab")
		)
		(fp_line
			(start -0.12065 0.3048)
			(end -0.67945 0.3048)
			(stroke
				(width 0.1)
				(type default)
			)
			(layer "F.Fab")
		)
		(fp_line
			(start 0.120396 0.2794)
			(end -0.12065 0.2794)
			(stroke
				(width 0.1)
				(type default)
			)
			(layer "F.Fab")
		)
		(fp_line
			(start 0.120396 0.3048)
			(end 0.120396 0.2794)
			(stroke
				(width 0.1)
				(type default)
			)
			(layer "F.Fab")
		)
		(fp_line
			(start 0.12065 -0.3048)
			(end 0.67945 -0.3048)
			(stroke
				(width 0.1)
				(type default)
			)
			(layer "F.Fab")
		)
		(fp_line
			(start 0.12065 -0.2794)
			(end 0.12065 -0.3048)
			(stroke
				(width 0.1)
				(type default)
			)
			(layer "F.Fab")
		)
		(fp_line
			(start 0.67945 -0.3048)
			(end 0.67945 0.3048)
			(stroke
				(width 0.1)
				(type default)
			)
			(layer "F.Fab")
		)
		(fp_line
			(start 0.67945 0.3048)
			(end 0.120396 0.3048)
			(stroke
				(width 0.1)
				(type default)
			)
			(layer "F.Fab")
		)
		(pad "1" smd circle
			(at -0.40005 0)
			(size 0 0)
			(layers "F.Cu" "F.Mask" "F.Paste")
			(net "SSD4_ADC_A0")
		)
		(pad "2" smd circle
			(at 0.40005 0)
			(size 0 0)
			(layers "F.Cu" "F.Mask" "F.Paste")
			(net "P3V3_AUX")
		)
	)
	(footprint ""
		(layer "F.Cu")
		(at 167.439086 -177.428398 -90)
		(property "Reference" "Q3"
			(at 0.745998 -1.878584 90)
			(unlocked yes)
			(layer "F.SilkS")
			(effects
				(font
					(size 0.7874 0.5842)
					(thickness 0.1524)
				)
				(justify left)
			)
		)
		(property "Value" ""
			(at 0 0 270)
			(layer "F.Fab")
			(effects
				(font
					(size 1.27 1.27)
				)
			)
		)
		(duplicate_pad_numbers_are_jumpers no)
		(fp_line
			(start -1.38176 1.100074)
			(end 1.38176 1.100074)
			(stroke
				(width 0.1524)
				(type default)
			)
			(layer "F.SilkS")
		)
		(fp_line
			(start 1.38176 1.100074)
			(end 1.38176 -1.100074)
			(stroke
				(width 0.1524)
				(type default)
			)
			(layer "F.SilkS")
		)
		(fp_line
			(start 0 -0.508)
			(end -0.592074 -1.100074)
			(stroke
				(width 0.1524)
				(type default)
			)
			(layer "F.SilkS")
		)
		(fp_line
			(start -1.38176 -1.100074)
			(end -1.38176 1.100074)
			(stroke
				(width 0.1524)
				(type default)
			)
			(layer "F.SilkS")
		)
		(fp_line
			(start -0.592074 -1.100074)
			(end -1.38176 -1.100074)
			(stroke
				(width 0.1524)
				(type default)
			)
			(layer "F.SilkS")
		)
		(fp_line
			(start 0.592074 -1.100074)
			(end 0 -0.508)
			(stroke
				(width 0.1524)
				(type default)
			)
			(layer "F.SilkS")
		)
		(fp_line
			(start 1.38176 -1.100074)
			(end 0.592074 -1.100074)
			(stroke
				(width 0.1524)
				(type default)
			)
			(layer "F.SilkS")
		)
		(fp_poly
			(pts
				(xy -1.745234 -1.571498) (xy -1.589278 -1.104392) (xy -2.056638 -1.260094)
			)
			(stroke
				(width 0)
				(type default)
			)
			(fill yes)
			(layer "F.SilkS")
		)
		(fp_line
			(start -0.674878 1.100074)
			(end 0.674878 1.100074)
			(stroke
				(width 0.1)
				(type default)
			)
			(layer "F.Fab")
		)
		(fp_line
			(start 0.674878 1.100074)
			(end 0.674878 -1.100074)
			(stroke
				(width 0.1)
				(type default)
			)
			(layer "F.Fab")
		)
		(fp_line
			(start -0.674878 -1.100074)
			(end -0.674878 1.100074)
			(stroke
				(width 0.1)
				(type default)
			)
			(layer "F.Fab")
		)
		(fp_line
			(start 0.674878 -1.100074)
			(end -0.674878 -1.100074)
			(stroke
				(width 0.1)
				(type default)
			)
			(layer "F.Fab")
		)
		(fp_poly
			(pts
				(xy -1.9431 -0.870204) (xy -1.50241 -0.649986) (xy -1.9431 -0.429768)
			)
			(stroke
				(width 0)
				(type default)
			)
			(fill yes)
			(layer "F.Fab")
		)
		(pad "1" smd rect
			(at -0.94996 -0.649986 180)
			(size 0.4318 0.6096)
			(layers "F.Cu" "F.Mask" "F.Paste")
			(net "GND")
		)
		(pad "2" smd rect
			(at -0.94996 0 180)
			(size 0.4318 0.6096)
			(layers "F.Cu" "F.Mask" "F.Paste")
			(net "HP_NIC2_HSC_PWRGD_N")
		)
		(pad "3" smd rect
			(at -0.94996 0.649986 180)
			(size 0.4318 0.6096)
			(layers "F.Cu" "F.Mask" "F.Paste")
			(net "HP_NIC2_HSC_PWRGD_N")
		)
		(pad "4" smd rect
			(at 0.94996 0.649986 180)
			(size 0.4318 0.6096)
			(layers "F.Cu" "F.Mask" "F.Paste")
			(net "GND")
		)
		(pad "5" smd rect
			(at 0.94996 0 180)
			(size 0.4318 0.6096)
			(layers "F.Cu" "F.Mask" "F.Paste")
			(net "PWRGD_P12V_NIC2_R")
		)
		(pad "6" smd rect
			(at 0.94996 -0.649986 180)
			(size 0.4318 0.6096)
			(layers "F.Cu" "F.Mask" "F.Paste")
			(net "HP_NIC2_PWRGD_R")
		)
	)
	(footprint ""
		(layer "F.Cu")
		(at 85.771736 -24.807418)
		(property "Reference" "R419"
			(at 0 0 0)
			(layer "F.SilkS")
			(hide yes)
			(effects
				(font
					(size 1.27 1.27)
				)
			)
		)
		(property "Value" ""
			(at 0 0 0)
			(layer "F.Fab")
			(effects
				(font
					(size 1.27 1.27)
				)
			)
		)
		(duplicate_pad_numbers_are_jumpers no)
		(fp_line
			(start -0.7874 -0.4064)
			(end 0.7874 -0.4064)
			(stroke
				(width 0.1524)
				(type default)
			)
			(layer "F.SilkS")
		)
		(fp_line
			(start -0.7874 0.4064)
			(end -0.7874 -0.4064)
			(stroke
				(width 0.1524)
				(type default)
			)
			(layer "F.SilkS")
		)
		(fp_line
			(start 0.7874 -0.4064)
			(end 0.7874 0.4064)
			(stroke
				(width 0.1524)
				(type default)
			)
			(layer "F.SilkS")
		)
		(fp_line
			(start 0.7874 0.4064)
			(end -0.7874 0.4064)
			(stroke
				(width 0.1524)
				(type default)
			)
			(layer "F.SilkS")
		)
		(fp_line
			(start -0.67945 -0.305054)
			(end -0.12065 -0.305054)
			(stroke
				(width 0.1)
				(type default)
			)
			(layer "F.Fab")
		)
		(fp_line
			(start -0.67945 0.3048)
			(end -0.67945 -0.305054)
			(stroke
				(width 0.1)
				(type default)
			)
			(layer "F.Fab")
		)
		(fp_line
			(start -0.12065 -0.305054)
			(end -0.12065 -0.2794)
			(stroke
				(width 0.1)
				(type default)
			)
			(layer "F.Fab")
		)
		(fp_line
			(start -0.12065 -0.2794)
			(end 0.12065 -0.2794)
			(stroke
				(width 0.1)
				(type default)
			)
			(layer "F.Fab")
		)
		(fp_line
			(start -0.12065 0.2794)
			(end -0.12065 0.3048)
			(stroke
				(width 0.1)
				(type default)
			)
			(layer "F.Fab")
		)
		(fp_line
			(start -0.12065 0.3048)
			(end -0.67945 0.3048)
			(stroke
				(width 0.1)
				(type default)
			)
			(layer "F.Fab")
		)
		(fp_line
			(start 0.120396 0.2794)
			(end -0.12065 0.2794)
			(stroke
				(width 0.1)
				(type default)
			)
			(layer "F.Fab")
		)
		(fp_line
			(start 0.120396 0.3048)
			(end 0.120396 0.2794)
			(stroke
				(width 0.1)
				(type default)
			)
			(layer "F.Fab")
		)
		(fp_line
			(start 0.12065 -0.3048)
			(end 0.67945 -0.3048)
			(stroke
				(width 0.1)
				(type default)
			)
			(layer "F.Fab")
		)
		(fp_line
			(start 0.12065 -0.2794)
			(end 0.12065 -0.3048)
			(stroke
				(width 0.1)
				(type default)
			)
			(layer "F.Fab")
		)
		(fp_line
			(start 0.67945 -0.3048)
			(end 0.67945 0.3048)
			(stroke
				(width 0.1)
				(type default)
			)
			(layer "F.Fab")
		)
		(fp_line
			(start 0.67945 0.3048)
			(end 0.120396 0.3048)
			(stroke
				(width 0.1)
				(type default)
			)
			(layer "F.Fab")
		)
		(pad "1" smd circle
			(at -0.40005 0)
			(size 0 0)
			(layers "F.Cu" "F.Mask" "F.Paste")
			(net "P3V3_SSD3")
		)
		(pad "2" smd circle
			(at 0.40005 0)
			(size 0 0)
			(layers "F.Cu" "F.Mask" "F.Paste")
			(net "PU_CLKREQ3")
		)
	)
	(footprint ""
		(layer "F.Cu")
		(at 62.808612 -158.080202 90)
		(property "Reference" "R2471"
			(at 0 0 90)
			(layer "F.SilkS")
			(hide yes)
			(effects
				(font
					(size 1.27 1.27)
				)
			)
		)
		(property "Value" ""
			(at 0 0 90)
			(layer "F.Fab")
			(effects
				(font
					(size 1.27 1.27)
				)
			)
		)
		(duplicate_pad_numbers_are_jumpers no)
		(fp_line
			(start 0.7874 -0.4064)
			(end 0.7874 0.4064)
			(stroke
				(width 0.1524)
				(type default)
			)
			(layer "F.SilkS")
		)
		(fp_line
			(start -0.7874 -0.4064)
			(end 0.7874 -0.4064)
			(stroke
				(width 0.1524)
				(type default)
			)
			(layer "F.SilkS")
		)
		(fp_line
			(start 0.7874 0.4064)
			(end -0.7874 0.4064)
			(stroke
				(width 0.1524)
				(type default)
			)
			(layer "F.SilkS")
		)
		(fp_line
			(start -0.7874 0.4064)
			(end -0.7874 -0.4064)
			(stroke
				(width 0.1524)
				(type default)
			)
			(layer "F.SilkS")
		)
		(fp_line
			(start -0.12065 -0.305054)
			(end -0.12065 -0.2794)
			(stroke
				(width 0.1)
				(type default)
			)
			(layer "F.Fab")
		)
		(fp_line
			(start -0.67945 -0.305054)
			(end -0.12065 -0.305054)
			(stroke
				(width 0.1)
				(type default)
			)
			(layer "F.Fab")
		)
		(fp_line
			(start 0.67945 -0.3048)
			(end 0.67945 0.3048)
			(stroke
				(width 0.1)
				(type default)
			)
			(layer "F.Fab")
		)
		(fp_line
			(start 0.12065 -0.3048)
			(end 0.67945 -0.3048)
			(stroke
				(width 0.1)
				(type default)
			)
			(layer "F.Fab")
		)
		(fp_line
			(start 0.12065 -0.2794)
			(end 0.12065 -0.3048)
			(stroke
				(width 0.1)
				(type default)
			)
			(layer "F.Fab")
		)
		(fp_line
			(start -0.12065 -0.2794)
			(end 0.12065 -0.2794)
			(stroke
				(width 0.1)
				(type default)
			)
			(layer "F.Fab")
		)
		(fp_line
			(start 0.120396 0.2794)
			(end -0.12065 0.2794)
			(stroke
				(width 0.1)
				(type default)
			)
			(layer "F.Fab")
		)
		(fp_line
			(start -0.12065 0.2794)
			(end -0.12065 0.3048)
			(stroke
				(width 0.1)
				(type default)
			)
			(layer "F.Fab")
		)
		(fp_line
			(start 0.67945 0.3048)
			(end 0.120396 0.3048)
			(stroke
				(width 0.1)
				(type default)
			)
			(layer "F.Fab")
		)
		(fp_line
			(start 0.120396 0.3048)
			(end 0.120396 0.2794)
			(stroke
				(width 0.1)
				(type default)
			)
			(layer "F.Fab")
		)
		(fp_line
			(start -0.12065 0.3048)
			(end -0.67945 0.3048)
			(stroke
				(width 0.1)
				(type default)
			)
			(layer "F.Fab")
		)
		(fp_line
			(start -0.67945 0.3048)
			(end -0.67945 -0.305054)
			(stroke
				(width 0.1)
				(type default)
			)
			(layer "F.Fab")
		)
		(pad "1" smd circle
			(at -0.40005 0 90)
			(size 0 0)
			(layers "F.Cu" "F.Mask" "F.Paste")
			(net "P3V3_NIC1")
		)
		(pad "2" smd circle
			(at 0.40005 0 90)
			(size 0 0)
			(layers "F.Cu" "F.Mask" "F.Paste")
			(net "NIC1_PWRBRK_N")
		)
	)
	(footprint ""
		(layer "F.Cu")
		(at 378.844302 -93.618304)
		(property "Reference" "R4109"
			(at 0 0 0)
			(layer "F.SilkS")
			(hide yes)
			(effects
				(font
					(size 1.27 1.27)
				)
			)
		)
		(property "Value" ""
			(at 0 0 0)
			(layer "F.Fab")
			(effects
				(font
					(size 1.27 1.27)
				)
			)
		)
		(duplicate_pad_numbers_are_jumpers no)
		(fp_line
			(start -0.7874 -0.4064)
			(end 0.7874 -0.4064)
			(stroke
				(width 0.1524)
				(type default)
			)
			(layer "F.SilkS")
		)
		(fp_line
			(start -0.7874 0.4064)
			(end -0.7874 -0.4064)
			(stroke
				(width 0.1524)
				(type default)
			)
			(layer "F.SilkS")
		)
		(fp_line
			(start 0.7874 -0.4064)
			(end 0.7874 0.4064)
			(stroke
				(width 0.1524)
				(type default)
			)
			(layer "F.SilkS")
		)
		(fp_line
			(start 0.7874 0.4064)
			(end -0.7874 0.4064)
			(stroke
				(width 0.1524)
				(type default)
			)
			(layer "F.SilkS")
		)
		(fp_line
			(start -0.67945 -0.305054)
			(end -0.12065 -0.305054)
			(stroke
				(width 0.1)
				(type default)
			)
			(layer "F.Fab")
		)
		(fp_line
			(start -0.67945 0.3048)
			(end -0.67945 -0.305054)
			(stroke
				(width 0.1)
				(type default)
			)
			(layer "F.Fab")
		)
		(fp_line
			(start -0.12065 -0.305054)
			(end -0.12065 -0.2794)
			(stroke
				(width 0.1)
				(type default)
			)
			(layer "F.Fab")
		)
		(fp_line
			(start -0.12065 -0.2794)
			(end 0.12065 -0.2794)
			(stroke
				(width 0.1)
				(type default)
			)
			(layer "F.Fab")
		)
		(fp_line
			(start -0.12065 0.2794)
			(end -0.12065 0.3048)
			(stroke
				(width 0.1)
				(type default)
			)
			(layer "F.Fab")
		)
		(fp_line
			(start -0.12065 0.3048)
			(end -0.67945 0.3048)
			(stroke
				(width 0.1)
				(type default)
			)
			(layer "F.Fab")
		)
		(fp_line
			(start 0.120396 0.2794)
			(end -0.12065 0.2794)
			(stroke
				(width 0.1)
				(type default)
			)
			(layer "F.Fab")
		)
		(fp_line
			(start 0.120396 0.3048)
			(end 0.120396 0.2794)
			(stroke
				(width 0.1)
				(type default)
			)
			(layer "F.Fab")
		)
		(fp_line
			(start 0.12065 -0.3048)
			(end 0.67945 -0.3048)
			(stroke
				(width 0.1)
				(type default)
			)
			(layer "F.Fab")
		)
		(fp_line
			(start 0.12065 -0.2794)
			(end 0.12065 -0.3048)
			(stroke
				(width 0.1)
				(type default)
			)
			(layer "F.Fab")
		)
		(fp_line
			(start 0.67945 -0.3048)
			(end 0.67945 0.3048)
			(stroke
				(width 0.1)
				(type default)
			)
			(layer "F.Fab")
		)
		(fp_line
			(start 0.67945 0.3048)
			(end 0.120396 0.3048)
			(stroke
				(width 0.1)
				(type default)
			)
			(layer "F.Fab")
		)
		(pad "1" smd circle
			(at -0.40005 0)
			(size 0 0)
			(layers "F.Cu" "F.Mask" "F.Paste")
			(net "SMB_BIC_I2C6_R_SDA")
		)
		(pad "2" smd circle
			(at 0.40005 0)
			(size 0 0)
			(layers "F.Cu" "F.Mask" "F.Paste")
			(net "SMB_BIC_I2C6_SENEOR_SDA")
		)
	)
	(footprint ""
		(layer "F.Cu")
		(at 198.905368 -112.394492 180)
		(property "Reference" "R183"
			(at 0 0 180)
			(layer "F.SilkS")
			(hide yes)
			(effects
				(font
					(size 1.27 1.27)
				)
			)
		)
		(property "Value" ""
			(at 0 0 180)
			(layer "F.Fab")
			(effects
				(font
					(size 1.27 1.27)
				)
			)
		)
		(duplicate_pad_numbers_are_jumpers no)
		(fp_line
			(start 0.7874 0.4064)
			(end -0.7874 0.4064)
			(stroke
				(width 0.1524)
				(type default)
			)
			(layer "F.SilkS")
		)
		(fp_line
			(start 0.7874 -0.4064)
			(end 0.7874 0.4064)
			(stroke
				(width 0.1524)
				(type default)
			)
			(layer "F.SilkS")
		)
		(fp_line
			(start -0.7874 0.4064)
			(end -0.7874 -0.4064)
			(stroke
				(width 0.1524)
				(type default)
			)
			(layer "F.SilkS")
		)
		(fp_line
			(start -0.7874 -0.4064)
			(end 0.7874 -0.4064)
			(stroke
				(width 0.1524)
				(type default)
			)
			(layer "F.SilkS")
		)
		(fp_line
			(start 0.67945 0.3048)
			(end 0.120396 0.3048)
			(stroke
				(width 0.1)
				(type default)
			)
			(layer "F.Fab")
		)
		(fp_line
			(start 0.67945 -0.3048)
			(end 0.67945 0.3048)
			(stroke
				(width 0.1)
				(type default)
			)
			(layer "F.Fab")
		)
		(fp_line
			(start 0.12065 -0.2794)
			(end 0.12065 -0.3048)
			(stroke
				(width 0.1)
				(type default)
			)
			(layer "F.Fab")
		)
		(fp_line
			(start 0.12065 -0.3048)
			(end 0.67945 -0.3048)
			(stroke
				(width 0.1)
				(type default)
			)
			(layer "F.Fab")
		)
		(fp_line
			(start 0.120396 0.3048)
			(end 0.120396 0.2794)
			(stroke
				(width 0.1)
				(type default)
			)
			(layer "F.Fab")
		)
		(fp_line
			(start 0.120396 0.2794)
			(end -0.12065 0.2794)
			(stroke
				(width 0.1)
				(type default)
			)
			(layer "F.Fab")
		)
		(fp_line
			(start -0.12065 0.3048)
			(end -0.67945 0.3048)
			(stroke
				(width 0.1)
				(type default)
			)
			(layer "F.Fab")
		)
		(fp_line
			(start -0.12065 0.2794)
			(end -0.12065 0.3048)
			(stroke
				(width 0.1)
				(type default)
			)
			(layer "F.Fab")
		)
		(fp_line
			(start -0.12065 -0.2794)
			(end 0.12065 -0.2794)
			(stroke
				(width 0.1)
				(type default)
			)
			(layer "F.Fab")
		)
		(fp_line
			(start -0.12065 -0.305054)
			(end -0.12065 -0.2794)
			(stroke
				(width 0.1)
				(type default)
			)
			(layer "F.Fab")
		)
		(fp_line
			(start -0.67945 0.3048)
			(end -0.67945 -0.305054)
			(stroke
				(width 0.1)
				(type default)
			)
			(layer "F.Fab")
		)
		(fp_line
			(start -0.67945 -0.305054)
			(end -0.12065 -0.305054)
			(stroke
				(width 0.1)
				(type default)
			)
			(layer "F.Fab")
		)
		(pad "1" smd circle
			(at -0.40005 0 180)
			(size 0 0)
			(layers "F.Cu" "F.Mask" "F.Paste")
			(net "NIC3_BIF0_N")
		)
		(pad "2" smd circle
			(at 0.40005 0 180)
			(size 0 0)
			(layers "F.Cu" "F.Mask" "F.Paste")
			(net "GND")
		)
	)
)
